(kicad_pcb
	(version 20260206)
	(generator "pcbnew")
	(generator_version "10.0")
	(general
		(thickness 1.6)
		(legacy_teardrops no)
	)
	(paper "A4")
	(title_block
		(title "01162023_DA0F0TEBIF0_F0T_Expander_BD_F_brd_V02_OCP.brd")
		(comment 1 "Grand Teton / footprints 5829-5833 of 9728")
	)
	(layers
		(0 "F.Cu" signal "TOP")
		(4 "In1.Cu" signal "GND")
		(6 "In2.Cu" signal "VCC")
		(8 "In3.Cu" signal "VCC1")
		(10 "In4.Cu" signal "GND1")
		(12 "In5.Cu" signal "IN1")
		(14 "In6.Cu" signal "GND2")
		(16 "In7.Cu" signal "IN2")
		(18 "In8.Cu" signal "GND3")
		(20 "In9.Cu" signal "IN3")
		(22 "In10.Cu" signal "GND4")
		(24 "In11.Cu" signal "IN4")
		(26 "In12.Cu" signal "GND5")
		(28 "In13.Cu" signal "IN5")
		(30 "In14.Cu" signal "GND6")
		(32 "In15.Cu" signal "IN6")
		(34 "In16.Cu" signal "GND7")
		(2 "B.Cu" signal "BOTTOM")
		(9 "F.Adhes" user "F.Adhesive")
		(11 "B.Adhes" user "B.Adhesive")
		(13 "F.Paste" user "Package Geometry/Pastemask Top")
		(15 "B.Paste" user "Package Geometry/Pastemask Bottom")
		(5 "F.SilkS" user "Ref Des/Silkscreen Top")
		(7 "B.SilkS" user "Ref Des/Silkscreen Bottom")
		(1 "F.Mask" user "Board Geometry/Soldermask Top")
		(3 "B.Mask" user "Board Geometry/Soldermask Bottom")
		(17 "Dwgs.User" user "User.Drawings")
		(19 "Cmts.User" user "User.Comments")
		(21 "Eco1.User" user "User.Eco1")
		(23 "Eco2.User" user "User.Eco2")
		(25 "Edge.Cuts" user "Board Geometry/Outline")
		(27 "Margin" user)
		(31 "F.CrtYd" user "Package Geometry/Place Bound Top")
		(29 "B.CrtYd" user "Package Geometry/Place Bound Bottom")
		(35 "F.Fab" user "Ref Des/Assembly Top")
		(33 "B.Fab" user "Ref Des/Assembly Bottom")
	)
	(footprint ""
		(layer "F.Cu")
		(at 294.029892 -171.661328 180)
		(property "Reference" "C919"
			(at 0 0 180)
			(layer "F.SilkS")
			(hide yes)
			(effects
				(font
					(size 1.27 1.27)
				)
			)
		)
		(property "Value" ""
			(at 0 0 180)
			(layer "F.Fab")
			(effects
				(font
					(size 1.27 1.27)
				)
			)
		)
		(duplicate_pad_numbers_are_jumpers no)
		(fp_line
			(start 0.7874 0.4064)
			(end -0.7874 0.4064)
			(stroke
				(width 0.1524)
				(type default)
			)
			(layer "F.SilkS")
		)
		(fp_line
			(start 0.7874 -0.4064)
			(end 0.7874 0.4064)
			(stroke
				(width 0.1524)
				(type default)
			)
			(layer "F.SilkS")
		)
		(fp_line
			(start -0.7874 0.4064)
			(end -0.7874 -0.4064)
			(stroke
				(width 0.1524)
				(type default)
			)
			(layer "F.SilkS")
		)
		(fp_line
			(start -0.7874 -0.4064)
			(end 0.7874 -0.4064)
			(stroke
				(width 0.1524)
				(type default)
			)
			(layer "F.SilkS")
		)
		(fp_line
			(start 0.67945 0.3048)
			(end 0.120396 0.3048)
			(stroke
				(width 0.1)
				(type default)
			)
			(layer "F.Fab")
		)
		(fp_line
			(start 0.67945 -0.3048)
			(end 0.67945 0.3048)
			(stroke
				(width 0.1)
				(type default)
			)
			(layer "F.Fab")
		)
		(fp_line
			(start 0.12065 -0.2794)
			(end 0.12065 -0.3048)
			(stroke
				(width 0.1)
				(type default)
			)
			(layer "F.Fab")
		)
		(fp_line
			(start 0.12065 -0.3048)
			(end 0.67945 -0.3048)
			(stroke
				(width 0.1)
				(type default)
			)
			(layer "F.Fab")
		)
		(fp_line
			(start 0.120396 0.3048)
			(end 0.120396 0.2794)
			(stroke
				(width 0.1)
				(type default)
			)
			(layer "F.Fab")
		)
		(fp_line
			(start 0.120396 0.2794)
			(end -0.12065 0.2794)
			(stroke
				(width 0.1)
				(type default)
			)
			(layer "F.Fab")
		)
		(fp_line
			(start -0.12065 0.3048)
			(end -0.67945 0.3048)
			(stroke
				(width 0.1)
				(type default)
			)
			(layer "F.Fab")
		)
		(fp_line
			(start -0.12065 0.2794)
			(end -0.12065 0.3048)
			(stroke
				(width 0.1)
				(type default)
			)
			(layer "F.Fab")
		)
		(fp_line
			(start -0.12065 -0.2794)
			(end 0.12065 -0.2794)
			(stroke
				(width 0.1)
				(type default)
			)
			(layer "F.Fab")
		)
		(fp_line
			(start -0.12065 -0.305054)
			(end -0.12065 -0.2794)
			(stroke
				(width 0.1)
				(type default)
			)
			(layer "F.Fab")
		)
		(fp_line
			(start -0.67945 0.3048)
			(end -0.67945 -0.305054)
			(stroke
				(width 0.1)
				(type default)
			)
			(layer "F.Fab")
		)
		(fp_line
			(start -0.67945 -0.305054)
			(end -0.12065 -0.305054)
			(stroke
				(width 0.1)
				(type default)
			)
			(layer "F.Fab")
		)
		(pad "1" smd circle
			(at -0.40005 0 180)
			(size 0 0)
			(layers "F.Cu" "F.Mask" "F.Paste")
			(net "P3V3_NIC4")
		)
		(pad "2" smd circle
			(at 0.40005 0 180)
			(size 0 0)
			(layers "F.Cu" "F.Mask" "F.Paste")
			(net "GND")
		)
	)
	(footprint ""
		(layer "F.Cu")
		(at 247.16232 -254.141224 -90)
		(property "Reference" "C4352"
			(at 0 0 270)
			(layer "F.SilkS")
			(hide yes)
			(effects
				(font
					(size 1.27 1.27)
				)
			)
		)
		(property "Value" ""
			(at 0 0 270)
			(layer "F.Fab")
			(effects
				(font
					(size 1.27 1.27)
				)
			)
		)
		(duplicate_pad_numbers_are_jumpers no)
		(fp_line
			(start -1.2954 0.5842)
			(end -1.2954 -0.5842)
			(stroke
				(width 0.1524)
				(type default)
			)
			(layer "F.SilkS")
		)
		(fp_line
			(start 1.2954 0.5842)
			(end -1.2954 0.5842)
			(stroke
				(width 0.1524)
				(type default)
			)
			(layer "F.SilkS")
		)
		(fp_line
			(start -1.2954 -0.5842)
			(end 1.2954 -0.5842)
			(stroke
				(width 0.1524)
				(type default)
			)
			(layer "F.SilkS")
		)
		(fp_line
			(start 1.2954 -0.5842)
			(end 1.2954 0.5842)
			(stroke
				(width 0.1524)
				(type default)
			)
			(layer "F.SilkS")
		)
		(fp_line
			(start -0.8636 0.4572)
			(end -0.8636 0.4064)
			(stroke
				(width 0.1)
				(type default)
			)
			(layer "F.Fab")
		)
		(fp_line
			(start 0.8636 0.4572)
			(end -0.8636 0.4572)
			(stroke
				(width 0.1)
				(type default)
			)
			(layer "F.Fab")
		)
		(fp_line
			(start -1.1938 0.4064)
			(end -1.1938 -0.4064)
			(stroke
				(width 0.1)
				(type default)
			)
			(layer "F.Fab")
		)
		(fp_line
			(start -0.8636 0.4064)
			(end -1.1938 0.4064)
			(stroke
				(width 0.1)
				(type default)
			)
			(layer "F.Fab")
		)
		(fp_line
			(start 0.8636 0.4064)
			(end 0.8636 0.4572)
			(stroke
				(width 0.1)
				(type default)
			)
			(layer "F.Fab")
		)
		(fp_line
			(start 1.1938 0.4064)
			(end 0.8636 0.4064)
			(stroke
				(width 0.1)
				(type default)
			)
			(layer "F.Fab")
		)
		(fp_line
			(start -1.1938 -0.4064)
			(end -0.8636 -0.4064)
			(stroke
				(width 0.1)
				(type default)
			)
			(layer "F.Fab")
		)
		(fp_line
			(start -0.8636 -0.4064)
			(end -0.8636 -0.4572)
			(stroke
				(width 0.1)
				(type default)
			)
			(layer "F.Fab")
		)
		(fp_line
			(start 0.8636 -0.4064)
			(end 1.1938 -0.4064)
			(stroke
				(width 0.1)
				(type default)
			)
			(layer "F.Fab")
		)
		(fp_line
			(start 1.1938 -0.4064)
			(end 1.1938 0.4064)
			(stroke
				(width 0.1)
				(type default)
			)
			(layer "F.Fab")
		)
		(fp_line
			(start -0.8636 -0.4572)
			(end 0.8636 -0.4572)
			(stroke
				(width 0.1)
				(type default)
			)
			(layer "F.Fab")
		)
		(fp_line
			(start 0.8636 -0.4572)
			(end 0.8636 -0.4064)
			(stroke
				(width 0.1)
				(type default)
			)
			(layer "F.Fab")
		)
		(pad "1" smd rect
			(at -0.7366 0 180)
			(size 0.7112 0.8128)
			(layers "F.Cu" "F.Mask" "F.Paste")
			(net "P1V25_SERDES_VDDPLL_PEX2_C6")
		)
		(pad "2" smd rect
			(at 0.7366 0 180)
			(size 0.7112 0.8128)
			(layers "F.Cu" "F.Mask" "F.Paste")
			(net "GND")
		)
	)
	(footprint ""
		(layer "F.Cu")
		(at 350.380554 -91.788234)
		(property "Reference" "R1597"
			(at 0 0 0)
			(layer "F.SilkS")
			(hide yes)
			(effects
				(font
					(size 1.27 1.27)
				)
			)
		)
		(property "Value" ""
			(at 0 0 0)
			(layer "F.Fab")
			(effects
				(font
					(size 1.27 1.27)
				)
			)
		)
		(duplicate_pad_numbers_are_jumpers no)
		(fp_line
			(start -0.7874 -0.4064)
			(end 0.7874 -0.4064)
			(stroke
				(width 0.1524)
				(type default)
			)
			(layer "F.SilkS")
		)
		(fp_line
			(start -0.7874 0.4064)
			(end -0.7874 -0.4064)
			(stroke
				(width 0.1524)
				(type default)
			)
			(layer "F.SilkS")
		)
		(fp_line
			(start 0.7874 -0.4064)
			(end 0.7874 0.4064)
			(stroke
				(width 0.1524)
				(type default)
			)
			(layer "F.SilkS")
		)
		(fp_line
			(start 0.7874 0.4064)
			(end -0.7874 0.4064)
			(stroke
				(width 0.1524)
				(type default)
			)
			(layer "F.SilkS")
		)
		(fp_line
			(start -0.67945 -0.305054)
			(end -0.12065 -0.305054)
			(stroke
				(width 0.1)
				(type default)
			)
			(layer "F.Fab")
		)
		(fp_line
			(start -0.67945 0.3048)
			(end -0.67945 -0.305054)
			(stroke
				(width 0.1)
				(type default)
			)
			(layer "F.Fab")
		)
		(fp_line
			(start -0.12065 -0.305054)
			(end -0.12065 -0.2794)
			(stroke
				(width 0.1)
				(type default)
			)
			(layer "F.Fab")
		)
		(fp_line
			(start -0.12065 -0.2794)
			(end 0.12065 -0.2794)
			(stroke
				(width 0.1)
				(type default)
			)
			(layer "F.Fab")
		)
		(fp_line
			(start -0.12065 0.2794)
			(end -0.12065 0.3048)
			(stroke
				(width 0.1)
				(type default)
			)
			(layer "F.Fab")
		)
		(fp_line
			(start -0.12065 0.3048)
			(end -0.67945 0.3048)
			(stroke
				(width 0.1)
				(type default)
			)
			(layer "F.Fab")
		)
		(fp_line
			(start 0.120396 0.2794)
			(end -0.12065 0.2794)
			(stroke
				(width 0.1)
				(type default)
			)
			(layer "F.Fab")
		)
		(fp_line
			(start 0.120396 0.3048)
			(end 0.120396 0.2794)
			(stroke
				(width 0.1)
				(type default)
			)
			(layer "F.Fab")
		)
		(fp_line
			(start 0.12065 -0.3048)
			(end 0.67945 -0.3048)
			(stroke
				(width 0.1)
				(type default)
			)
			(layer "F.Fab")
		)
		(fp_line
			(start 0.12065 -0.2794)
			(end 0.12065 -0.3048)
			(stroke
				(width 0.1)
				(type default)
			)
			(layer "F.Fab")
		)
		(fp_line
			(start 0.67945 -0.3048)
			(end 0.67945 0.3048)
			(stroke
				(width 0.1)
				(type default)
			)
			(layer "F.Fab")
		)
		(fp_line
			(start 0.67945 0.3048)
			(end 0.120396 0.3048)
			(stroke
				(width 0.1)
				(type default)
			)
			(layer "F.Fab")
		)
		(pad "1" smd circle
			(at -0.40005 0)
			(size 0 0)
			(layers "F.Cu" "F.Mask" "F.Paste")
			(net "P3V3_AUX")
		)
		(pad "2" smd circle
			(at 0.40005 0)
			(size 0 0)
			(layers "F.Cu" "F.Mask" "F.Paste")
			(net "BIC_I2C9_SSD_MUX1_A0")
		)
	)
	(footprint ""
		(layer "F.Cu")
		(at 277.198582 -343.952322 90)
		(property "Reference" "C605"
			(at 0 0 90)
			(layer "F.SilkS")
			(hide yes)
			(effects
				(font
					(size 1.27 1.27)
				)
			)
		)
		(property "Value" ""
			(at 0 0 90)
			(layer "F.Fab")
			(effects
				(font
					(size 1.27 1.27)
				)
			)
		)
		(duplicate_pad_numbers_are_jumpers no)
		(fp_line
			(start 0.299974 -0.150114)
			(end 0.299974 0.150114)
			(stroke
				(width 0.1)
				(type default)
			)
			(layer "F.Fab")
		)
		(fp_line
			(start -0.299974 -0.150114)
			(end 0.299974 -0.150114)
			(stroke
				(width 0.1)
				(type default)
			)
			(layer "F.Fab")
		)
		(fp_line
			(start 0.299974 0.150114)
			(end -0.299974 0.150114)
			(stroke
				(width 0.1)
				(type default)
			)
			(layer "F.Fab")
		)
		(fp_line
			(start -0.299974 0.150114)
			(end -0.299974 -0.150114)
			(stroke
				(width 0.1)
				(type default)
			)
			(layer "F.Fab")
		)
		(pad "1" smd rect
			(at -0.2667 0 90)
			(size 0.3048 0.381)
			(layers "F.Cu" "F.Mask" "F.Paste")
			(net "P5E_PEX2_STN7_TX_DP<116>")
		)
		(pad "2" smd rect
			(at 0.2667 0 90)
			(size 0.3048 0.381)
			(layers "F.Cu" "F.Mask" "F.Paste")
			(net "P5E_PEX2_STN7_TX_C_DP<116>")
		)
	)
	(footprint ""
		(layer "F.Cu")
		(at 257.521964 -369.900962 90)
		(property "Reference" "PQ6604"
			(at -8.228584 -2.05994 0)
			(unlocked yes)
			(layer "F.SilkS")
			(effects
				(font
					(size 0.7874 0.5842)
					(thickness 0.1524)
				)
				(justify left)
			)
		)
		(property "Value" ""
			(at 0 0 90)
			(layer "F.Fab")
			(effects
				(font
					(size 1.27 1.27)
				)
			)
		)
		(duplicate_pad_numbers_are_jumpers no)
		(fp_line
			(start 2.350008 -2.649982)
			(end 2.350008 -2.4892)
			(stroke
				(width 0.1524)
				(type default)
			)
			(layer "F.SilkS")
		)
		(fp_line
			(start -2.350008 -2.649982)
			(end 2.350008 -2.649982)
			(stroke
				(width 0.1524)
				(type default)
			)
			(layer "F.SilkS")
		)
		(fp_line
			(start -2.350008 -2.4384)
			(end -2.350008 -2.649982)
			(stroke
				(width 0.1524)
				(type default)
			)
			(layer "F.SilkS")
		)
		(fp_line
			(start 2.350008 2.4892)
			(end 2.350008 2.649982)
			(stroke
				(width 0.1524)
				(type default)
			)
			(layer "F.SilkS")
		)
		(fp_line
			(start 2.350008 2.649982)
			(end -2.350008 2.649982)
			(stroke
				(width 0.1524)
				(type default)
			)
			(layer "F.SilkS")
		)
		(fp_line
			(start -2.350008 2.649982)
			(end -2.350008 2.413)
			(stroke
				(width 0.1524)
				(type default)
			)
			(layer "F.SilkS")
		)
		(fp_poly
			(pts
				(xy -3.717544 -1.905) (xy -4.758944 -2.3241) (xy -4.758944 -1.524)
			)
			(stroke
				(width 0)
				(type default)
			)
			(fill yes)
			(layer "F.SilkS")
		)
		(fp_line
			(start 2.350008 -2.649982)
			(end 2.350008 2.649982)
			(stroke
				(width 0.1)
				(type default)
			)
			(layer "F.Fab")
		)
		(fp_line
			(start -2.350008 -2.649982)
			(end 2.350008 -2.649982)
			(stroke
				(width 0.1)
				(type default)
			)
			(layer "F.Fab")
		)
		(fp_line
			(start 2.350008 2.649982)
			(end -2.350008 2.649982)
			(stroke
				(width 0.1)
				(type default)
			)
			(layer "F.Fab")
		)
		(fp_line
			(start -2.350008 2.649982)
			(end -2.350008 -2.649982)
			(stroke
				(width 0.1)
				(type default)
			)
			(layer "F.Fab")
		)
		(fp_poly
			(pts
				(xy -3.717544 -1.905) (xy -4.758944 -2.3241) (xy -4.758944 -1.524)
			)
			(stroke
				(width 0)
				(type default)
			)
			(fill yes)
			(layer "F.Fab")
		)
		(pad "1" smd rect
			(at -2.999994 -1.905)
			(size 0.7112 1.1684)
			(layers "F.Cu" "F.Mask" "F.Paste")
			(net "P12V_AUX")
		)
		(pad "2" smd rect
			(at -2.999994 -0.635)
			(size 0.7112 1.1684)
			(layers "F.Cu" "F.Mask" "F.Paste")
			(net "P12V_AUX")
		)
		(pad "3" smd rect
			(at -2.999994 0.635)
			(size 0.7112 1.1684)
			(layers "F.Cu" "F.Mask" "F.Paste")
			(net "P12V_AUX")
		)
		(pad "4" smd rect
			(at -2.999994 1.905)
			(size 0.7112 1.1684)
			(layers "F.Cu" "F.Mask" "F.Paste")
			(net "HS_GATE2_R_3")
		)
		(pad "5" smd circle
			(at 0.925068 0)
			(size 0 0)
			(layers "F.Cu" "F.Mask" "F.Paste")
			(net "P12V_STBY_R2")
		)
		(zone
			(layer "F.Cu")
			(hatch none 0.5)
			(connect_pads
				(clearance 0)
			)
			(min_thickness 0.25)
			(keepout
				(tracks not_allowed)
				(vias allowed)
				(pads allowed)
				(copperpour not_allowed)
				(footprints allowed)
			)
			(placement
				(enabled no)
				(sheetname "")
			)
			(fill
				(thermal_gap 0.5)
				(thermal_bridge_width 0.5)
				(island_removal_mode 0)
			)
			(polygon
				(pts
					(xy 255.362964 -368.453162) (xy 259.680964 -368.453162) (xy 260.163564 -368.453162) (xy 260.163564 -367.551462)
					(xy 254.880364 -367.551462) (xy 254.880364 -368.453162)
				)
			)
		)
	)
)
